# S9S_MB_2U (Grand Teton) — schematic netlist excerpt (pin names and nets, part order shuffled) for the footprints in the layout excerpt that follows; sources: Cadence DE-HDL packaged netlist, KiCad conversion of 03242023_DA0F0TMBIJ0_F0T_Motherboard_J_brd_V01_OCP.brd

C143  Q_CAP_DIFFBUS  DIFF BUS_0.22UF 6.3V 20% X6S  pkg C0201  page 178 : \1\ = DMI_CPU0_PCH_TX_C_DN<5> ; \2\ = DMI_CPU0_PCH_TX_DN<5>
PC222  Q_CAP  470PF 50V 10% X7R  pkg 0402  page 274 : A = PVCCINFAON_CPU0_ATSEN ; B = GND
PC1866  Q_CAPP  560UF 6.3V 20% OSCON  pkg THLF  page 259 : A = P3V3_AUX ; B = GND

(kicad_pcb
	(version 20260206)
	(generator "pcbnew")
	(generator_version "10.0")
	(general
		(thickness 1.6)
		(legacy_teardrops no)
	)
	(paper "A4")
	(title_block
		(title "03242023_DA0F0TMBIJ0_F0T_Motherboard_J_brd_V01_OCP.brd")
		(comment 1 "Grand Teton / footprints 675-677 of 6105")
	)
	(layers
		(0 "F.Cu" signal "TOP")
		(4 "In1.Cu" signal "GND")
		(6 "In2.Cu" signal "IN1")
		(8 "In3.Cu" signal "GND1")
		(10 "In4.Cu" signal "IN2")
		(12 "In5.Cu" signal "GND2")
		(14 "In6.Cu" signal "IN3")
		(16 "In7.Cu" signal "GND3")
		(18 "In8.Cu" signal "VCC")
		(20 "In9.Cu" signal "VCC1")
		(22 "In10.Cu" signal "GND4")
		(24 "In11.Cu" signal "IN4")
		(26 "In12.Cu" signal "GND5")
		(28 "In13.Cu" signal "IN5")
		(30 "In14.Cu" signal "GND6")
		(32 "In15.Cu" signal "IN6")
		(34 "In16.Cu" signal "GND7")
		(2 "B.Cu" signal "BOTTOM")
		(9 "F.Adhes" user "F.Adhesive")
		(11 "B.Adhes" user "B.Adhesive")
		(13 "F.Paste" user "Package Geometry/Pastemask Top")
		(15 "B.Paste" user "Package Geometry/Pastemask Bottom")
		(5 "F.SilkS" user "Ref Des/Silkscreen Top")
		(7 "B.SilkS" user "Ref Des/Silkscreen Bottom")
		(1 "F.Mask" user "Board Geometry/Soldermask Top")
		(3 "B.Mask" user "Board Geometry/Soldermask Bottom")
		(17 "Dwgs.User" user "User.Drawings")
		(19 "Cmts.User" user "User.Comments")
		(21 "Eco1.User" user "User.Eco1")
		(23 "Eco2.User" user "User.Eco2")
		(25 "Edge.Cuts" user "Board Geometry/Outline")
		(27 "Margin" user)
		(31 "F.CrtYd" user "Package Geometry/Place Bound Top")
		(29 "B.CrtYd" user "Package Geometry/Place Bound Bottom")
		(35 "F.Fab" user "Ref Des/Assembly Top")
		(33 "B.Fab" user "Ref Des/Assembly Bottom")
	)
	(footprint ""
		(layer "F.Cu")
		(at 351.6757 -64.440562)
		(property "Reference" "C143"
			(at 0 0 0)
			(layer "F.SilkS")
			(hide yes)
			(effects
				(font
					(size 1.27 1.27)
				)
			)
		)
		(property "Value" ""
			(at 0 0 0)
			(layer "F.Fab")
			(effects
				(font
					(size 1.27 1.27)
				)
			)
		)
		(duplicate_pad_numbers_are_jumpers no)
		(fp_line
			(start -0.299974 -0.150114)
			(end 0.299974 -0.150114)
			(stroke
				(width 0.1)
				(type default)
			)
			(layer "F.Fab")
		)
		(fp_line
			(start -0.299974 0.150114)
			(end -0.299974 -0.150114)
			(stroke
				(width 0.1)
				(type default)
			)
			(layer "F.Fab")
		)
		(fp_line
			(start 0.299974 -0.150114)
			(end 0.299974 0.150114)
			(stroke
				(width 0.1)
				(type default)
			)
			(layer "F.Fab")
		)
		(fp_line
			(start 0.299974 0.150114)
			(end -0.299974 0.150114)
			(stroke
				(width 0.1)
				(type default)
			)
			(layer "F.Fab")
		)
		(pad "1" smd rect
			(at -0.2667 0)
			(size 0.3048 0.381)
			(layers "F.Cu" "F.Mask" "F.Paste")
			(net "DMI_CPU0_PCH_TX_C_DN<5>")
		)
		(pad "2" smd rect
			(at 0.2667 0)
			(size 0.3048 0.381)
			(layers "F.Cu" "F.Mask" "F.Paste")
			(net "DMI_CPU0_PCH_TX_DN<5>")
		)
		(zone
			(layer "In1.Cu")
			(hatch none 0.5)
			(connect_pads
				(clearance 0)
			)
			(min_thickness 0.25)
			(keepout
				(tracks not_allowed)
				(vias allowed)
				(pads allowed)
				(copperpour not_allowed)
				(footprints allowed)
			)
			(placement
				(enabled no)
				(sheetname "")
			)
			(fill
				(thermal_gap 0.5)
				(thermal_bridge_width 0.5)
				(island_removal_mode 0)
			)
			(polygon
				(pts
					(arc
						(start 351.282 -64.199262)
						(mid 351.228118 -64.22158)
						(end 351.2058 -64.275462)
					)
					(arc
						(start 351.2058 -64.605662)
						(mid 351.228118 -64.659544)
						(end 351.282 -64.681862)
					)
					(arc
						(start 351.536 -64.681862)
						(mid 351.589882 -64.659544)
						(end 351.6122 -64.605662)
					)
					(arc
						(start 351.6122 -64.275462)
						(mid 351.589882 -64.22158)
						(end 351.536 -64.199262)
					)
				)
			)
		)
		(zone
			(layer "In1.Cu")
			(hatch none 0.5)
			(connect_pads
				(clearance 0)
			)
			(min_thickness 0.25)
			(keepout
				(tracks not_allowed)
				(vias allowed)
				(pads allowed)
				(copperpour not_allowed)
				(footprints allowed)
			)
			(placement
				(enabled no)
				(sheetname "")
			)
			(fill
				(thermal_gap 0.5)
				(thermal_bridge_width 0.5)
				(island_removal_mode 0)
			)
			(polygon
				(pts
					(arc
						(start 351.8154 -64.199262)
						(mid 351.761518 -64.22158)
						(end 351.7392 -64.275462)
					)
					(arc
						(start 351.7392 -64.605662)
						(mid 351.761518 -64.659544)
						(end 351.8154 -64.681862)
					)
					(arc
						(start 352.0694 -64.681862)
						(mid 352.123282 -64.659544)
						(end 352.1456 -64.605662)
					)
					(arc
						(start 352.1456 -64.275462)
						(mid 352.123282 -64.22158)
						(end 352.0694 -64.199262)
					)
				)
			)
		)
	)
	(footprint ""
		(layer "F.Cu")
		(at 420.682166 -137.178034 180)
		(property "Reference" "PC222"
			(at 0 0 180)
			(layer "F.SilkS")
			(hide yes)
			(effects
				(font
					(size 1.27 1.27)
				)
			)
		)
		(property "Value" ""
			(at 0 0 180)
			(layer "F.Fab")
			(effects
				(font
					(size 1.27 1.27)
				)
			)
		)
		(duplicate_pad_numbers_are_jumpers no)
		(fp_line
			(start 0.7874 0.4064)
			(end -0.7874 0.4064)
			(stroke
				(width 0.1524)
				(type default)
			)
			(layer "F.SilkS")
		)
		(fp_line
			(start 0.7874 -0.4064)
			(end 0.7874 0.4064)
			(stroke
				(width 0.1524)
				(type default)
			)
			(layer "F.SilkS")
		)
		(fp_line
			(start -0.7874 0.4064)
			(end -0.7874 -0.4064)
			(stroke
				(width 0.1524)
				(type default)
			)
			(layer "F.SilkS")
		)
		(fp_line
			(start -0.7874 -0.4064)
			(end 0.7874 -0.4064)
			(stroke
				(width 0.1524)
				(type default)
			)
			(layer "F.SilkS")
		)
		(fp_line
			(start 0.67945 0.3048)
			(end 0.120396 0.3048)
			(stroke
				(width 0.1)
				(type default)
			)
			(layer "F.Fab")
		)
		(fp_line
			(start 0.67945 -0.3048)
			(end 0.67945 0.3048)
			(stroke
				(width 0.1)
				(type default)
			)
			(layer "F.Fab")
		)
		(fp_line
			(start 0.12065 -0.2794)
			(end 0.12065 -0.3048)
			(stroke
				(width 0.1)
				(type default)
			)
			(layer "F.Fab")
		)
		(fp_line
			(start 0.12065 -0.3048)
			(end 0.67945 -0.3048)
			(stroke
				(width 0.1)
				(type default)
			)
			(layer "F.Fab")
		)
		(fp_line
			(start 0.120396 0.3048)
			(end 0.120396 0.2794)
			(stroke
				(width 0.1)
				(type default)
			)
			(layer "F.Fab")
		)
		(fp_line
			(start 0.120396 0.2794)
			(end -0.12065 0.2794)
			(stroke
				(width 0.1)
				(type default)
			)
			(layer "F.Fab")
		)
		(fp_line
			(start -0.12065 0.3048)
			(end -0.67945 0.3048)
			(stroke
				(width 0.1)
				(type default)
			)
			(layer "F.Fab")
		)
		(fp_line
			(start -0.12065 0.2794)
			(end -0.12065 0.3048)
			(stroke
				(width 0.1)
				(type default)
			)
			(layer "F.Fab")
		)
		(fp_line
			(start -0.12065 -0.2794)
			(end 0.12065 -0.2794)
			(stroke
				(width 0.1)
				(type default)
			)
			(layer "F.Fab")
		)
		(fp_line
			(start -0.12065 -0.305054)
			(end -0.12065 -0.2794)
			(stroke
				(width 0.1)
				(type default)
			)
			(layer "F.Fab")
		)
		(fp_line
			(start -0.67945 0.3048)
			(end -0.67945 -0.305054)
			(stroke
				(width 0.1)
				(type default)
			)
			(layer "F.Fab")
		)
		(fp_line
			(start -0.67945 -0.305054)
			(end -0.12065 -0.305054)
			(stroke
				(width 0.1)
				(type default)
			)
			(layer "F.Fab")
		)
		(pad "1" smd circle
			(at -0.40005 0 180)
			(size 0 0)
			(layers "F.Cu" "F.Mask" "F.Paste")
			(net "PVCCINFAON_CPU0_ATSEN")
		)
		(pad "2" smd circle
			(at 0.40005 0 180)
			(size 0 0)
			(layers "F.Cu" "F.Mask" "F.Paste")
			(net "GND")
		)
	)
	(footprint ""
		(layer "F.Cu")
		(at 449.52666 -51.976528)
		(property "Reference" "PC1866"
			(at 0 0 0)
			(layer "F.SilkS")
			(hide yes)
			(effects
				(font
					(size 1.27 1.27)
				)
			)
		)
		(property "Value" ""
			(at 0 0 0)
			(layer "F.Fab")
			(effects
				(font
					(size 1.27 1.27)
				)
			)
		)
		(duplicate_pad_numbers_are_jumpers no)
		(fp_line
			(start -3.400044 1.249934)
			(end 3.400044 1.249934)
			(stroke
				(width 0.1524)
				(type default)
			)
			(layer "F.SilkS")
		)
		(fp_circle
			(center 0 1.249934)
			(end 3.400044 1.249934)
			(stroke
				(width 0.1524)
				(type default)
			)
			(fill no)
			(layer "F.SilkS")
		)
		(fp_poly
			(pts
				(arc
					(start 3.400044 1.249934)
					(mid 0 4.649978)
					(end -3.400044 1.249934)
				)
			)
			(stroke
				(width 0)
				(type default)
			)
			(fill yes)
			(layer "F.SilkS")
		)
		(fp_circle
			(center 0 1.249934)
			(end 3.400044 1.249934)
			(stroke
				(width 0.1)
				(type default)
			)
			(fill no)
			(layer "F.Fab")
		)
		(pad "1" thru_hole rect
			(at 0 0)
			(size 1.524 1.524)
			(drill 1.016)
			(layers "*.Cu" "*.Mask")
			(remove_unused_layers no)
			(net "P3V3_AUX")
			(clearance 0)
			(padstack
				(mode front_inner_back)
				(layer "Inner"
					(shape circle)
					(size 1.524 1.524)
					(clearance 0)
				)
				(layer "B.Cu"
					(shape rect)
					(size 1.524 1.524)
					(clearance 0)
				)
			)
		)
		(pad "2" thru_hole circle
			(at 0 2.500122)
			(size 1.524 1.524)
			(drill 1.016)
			(layers "*.Cu" "*.Mask")
			(remove_unused_layers no)
			(net "GND")
			(clearance 0)
		)
	)
)
